# T6G (Grand Teton) — schematic netlist excerpt (pin names and nets, part order shuffled) for the footprints in the layout excerpt that follows; sources: Cadence DE-HDL packaged netlist, KiCad conversion of 04192023_DAF0TMB3IC0_F0TG_MB_C_brd_V02_OCP.brd

PL6500  Q_INDUCTOR  100NH/16A IND  pkg SMLF  page 360 : \1\ = P12V_AUX ; \2\ = SW_P12V_AUX_P1V8_RETIMER_CPU0_FLT
R2933  Q_RES  100K 1% CHIP  pkg 0402LF  page 127 : A = P3V3_AUX ; B = FM_SWB_BIC_READY_ISO_N
R994  Q_RES  10K 1% CHIP  pkg 0402LF  page 155 : A = P3V3_AUX ; B = IRQ_LVC3_WAKE_N

(kicad_pcb
	(version 20260206)
	(generator "pcbnew")
	(generator_version "10.0")
	(general
		(thickness 1.6)
		(legacy_teardrops no)
	)
	(paper "A4")
	(title_block
		(title "04192023_DAF0TMB3IC0_F0TG_MB_C_brd_V02_OCP.brd")
		(comment 1 "Grand Teton / footprints 2217-2219 of 8354")
	)
	(layers
		(0 "F.Cu" signal "TOP")
		(4 "In1.Cu" signal "GND")
		(6 "In2.Cu" signal "IN1")
		(8 "In3.Cu" signal "GND1")
		(10 "In4.Cu" signal "IN2")
		(12 "In5.Cu" signal "GND2")
		(14 "In6.Cu" signal "IN3")
		(16 "In7.Cu" signal "GND3")
		(18 "In8.Cu" signal "VCC")
		(20 "In9.Cu" signal "VCC1")
		(22 "In10.Cu" signal "GND4")
		(24 "In11.Cu" signal "IN4")
		(26 "In12.Cu" signal "GND5")
		(28 "In13.Cu" signal "IN5")
		(30 "In14.Cu" signal "GND6")
		(32 "In15.Cu" signal "IN6")
		(34 "In16.Cu" signal "GND7")
		(2 "B.Cu" signal "BOTTOM")
		(9 "F.Adhes" user "F.Adhesive")
		(11 "B.Adhes" user "B.Adhesive")
		(13 "F.Paste" user "Package Geometry/Pastemask Top")
		(15 "B.Paste" user "Package Geometry/Pastemask Bottom")
		(5 "F.SilkS" user "Ref Des/Silkscreen Top")
		(7 "B.SilkS" user "Ref Des/Silkscreen Bottom")
		(1 "F.Mask" user "Board Geometry/Soldermask Top")
		(3 "B.Mask" user "Board Geometry/Soldermask Bottom")
		(17 "Dwgs.User" user "User.Drawings")
		(19 "Cmts.User" user "User.Comments")
		(21 "Eco1.User" user "User.Eco1")
		(23 "Eco2.User" user "User.Eco2")
		(25 "Edge.Cuts" user "Board Geometry/Outline")
		(27 "Margin" user)
		(31 "F.CrtYd" user "Package Geometry/Place Bound Top")
		(29 "B.CrtYd" user "Package Geometry/Place Bound Bottom")
		(35 "F.Fab" user "Ref Des/Assembly Top")
		(33 "B.Fab" user "Ref Des/Assembly Bottom")
	)
	(footprint ""
		(layer "F.Cu")
		(at 248.46915 -271.267936 180)
		(property "Reference" "PL6500"
			(at 5.77215 -3.197606 0)
			(unlocked yes)
			(layer "F.SilkS")
			(effects
				(font
					(size 0.7874 0.5842)
					(thickness 0.1524)
				)
				(justify left)
			)
		)
		(property "Value" ""
			(at 0 0 180)
			(layer "F.Fab")
			(effects
				(font
					(size 1.27 1.27)
				)
			)
		)
		(duplicate_pad_numbers_are_jumpers no)
		(fp_line
			(start 2.249932 2.249932)
			(end -2.249932 2.249932)
			(stroke
				(width 0.1524)
				(type default)
			)
			(layer "F.SilkS")
		)
		(fp_line
			(start 2.249932 1.3843)
			(end 2.249932 2.249932)
			(stroke
				(width 0.1524)
				(type default)
			)
			(layer "F.SilkS")
		)
		(fp_line
			(start 2.249932 -2.249932)
			(end 2.249932 -1.3843)
			(stroke
				(width 0.1524)
				(type default)
			)
			(layer "F.SilkS")
		)
		(fp_line
			(start -2.249932 2.249932)
			(end -2.249932 1.3843)
			(stroke
				(width 0.1524)
				(type default)
			)
			(layer "F.SilkS")
		)
		(fp_line
			(start -2.249932 -1.3843)
			(end -2.249932 -2.249932)
			(stroke
				(width 0.1524)
				(type default)
			)
			(layer "F.SilkS")
		)
		(fp_line
			(start -2.249932 -2.249932)
			(end 2.249932 -2.249932)
			(stroke
				(width 0.1524)
				(type default)
			)
			(layer "F.SilkS")
		)
		(fp_line
			(start 2.249932 2.249932)
			(end -2.249932 2.249932)
			(stroke
				(width 0.1)
				(type default)
			)
			(layer "F.Fab")
		)
		(fp_line
			(start 2.249932 -2.249932)
			(end 2.249932 2.249932)
			(stroke
				(width 0.1)
				(type default)
			)
			(layer "F.Fab")
		)
		(fp_line
			(start -2.249932 2.249932)
			(end -2.249932 -2.249932)
			(stroke
				(width 0.1)
				(type default)
			)
			(layer "F.Fab")
		)
		(fp_line
			(start -2.249932 -2.249932)
			(end 2.249932 -2.249932)
			(stroke
				(width 0.1)
				(type default)
			)
			(layer "F.Fab")
		)
		(pad "1" smd rect
			(at -1.82499 0 180)
			(size 1.0668 2.5146)
			(layers "F.Cu" "F.Mask" "F.Paste")
			(net "P12V_AUX")
		)
		(pad "2" smd rect
			(at 1.82499 0 180)
			(size 1.0668 2.5146)
			(layers "F.Cu" "F.Mask" "F.Paste")
			(net "SW_P12V_AUX_P1V8_RETIMER_CPU0_FLT")
		)
	)
	(footprint ""
		(layer "F.Cu")
		(at 159.18307 -76.53147 -90)
		(property "Reference" "R994"
			(at 0 0 270)
			(layer "F.SilkS")
			(hide yes)
			(effects
				(font
					(size 1.27 1.27)
				)
			)
		)
		(property "Value" ""
			(at 0 0 270)
			(layer "F.Fab")
			(effects
				(font
					(size 1.27 1.27)
				)
			)
		)
		(duplicate_pad_numbers_are_jumpers no)
		(fp_line
			(start -0.7874 0.4064)
			(end -0.7874 -0.4064)
			(stroke
				(width 0.1524)
				(type default)
			)
			(layer "F.SilkS")
		)
		(fp_line
			(start 0.7874 0.4064)
			(end -0.7874 0.4064)
			(stroke
				(width 0.1524)
				(type default)
			)
			(layer "F.SilkS")
		)
		(fp_line
			(start -0.7874 -0.4064)
			(end 0.7874 -0.4064)
			(stroke
				(width 0.1524)
				(type default)
			)
			(layer "F.SilkS")
		)
		(fp_line
			(start 0.7874 -0.4064)
			(end 0.7874 0.4064)
			(stroke
				(width 0.1524)
				(type default)
			)
			(layer "F.SilkS")
		)
		(fp_line
			(start -0.67945 0.3048)
			(end -0.67945 -0.305054)
			(stroke
				(width 0.1)
				(type default)
			)
			(layer "F.Fab")
		)
		(fp_line
			(start -0.12065 0.3048)
			(end -0.67945 0.3048)
			(stroke
				(width 0.1)
				(type default)
			)
			(layer "F.Fab")
		)
		(fp_line
			(start 0.120396 0.3048)
			(end 0.120396 0.2794)
			(stroke
				(width 0.1)
				(type default)
			)
			(layer "F.Fab")
		)
		(fp_line
			(start 0.67945 0.3048)
			(end 0.120396 0.3048)
			(stroke
				(width 0.1)
				(type default)
			)
			(layer "F.Fab")
		)
		(fp_line
			(start -0.12065 0.2794)
			(end -0.12065 0.3048)
			(stroke
				(width 0.1)
				(type default)
			)
			(layer "F.Fab")
		)
		(fp_line
			(start 0.120396 0.2794)
			(end -0.12065 0.2794)
			(stroke
				(width 0.1)
				(type default)
			)
			(layer "F.Fab")
		)
		(fp_line
			(start -0.12065 -0.2794)
			(end 0.12065 -0.2794)
			(stroke
				(width 0.1)
				(type default)
			)
			(layer "F.Fab")
		)
		(fp_line
			(start 0.12065 -0.2794)
			(end 0.12065 -0.3048)
			(stroke
				(width 0.1)
				(type default)
			)
			(layer "F.Fab")
		)
		(fp_line
			(start 0.12065 -0.3048)
			(end 0.67945 -0.3048)
			(stroke
				(width 0.1)
				(type default)
			)
			(layer "F.Fab")
		)
		(fp_line
			(start 0.67945 -0.3048)
			(end 0.67945 0.3048)
			(stroke
				(width 0.1)
				(type default)
			)
			(layer "F.Fab")
		)
		(fp_line
			(start -0.67945 -0.305054)
			(end -0.12065 -0.305054)
			(stroke
				(width 0.1)
				(type default)
			)
			(layer "F.Fab")
		)
		(fp_line
			(start -0.12065 -0.305054)
			(end -0.12065 -0.2794)
			(stroke
				(width 0.1)
				(type default)
			)
			(layer "F.Fab")
		)
		(pad "1" smd circle
			(at -0.40005 0 270)
			(size 0 0)
			(layers "F.Cu" "F.Mask" "F.Paste")
			(net "P3V3_AUX")
		)
		(pad "2" smd circle
			(at 0.40005 0 270)
			(size 0 0)
			(layers "F.Cu" "F.Mask" "F.Paste")
			(net "IRQ_LVC3_WAKE_N")
		)
	)
	(footprint ""
		(layer "F.Cu")
		(at 428.120302 -434.386736 90)
		(property "Reference" "R2933"
			(at 0 0 90)
			(layer "F.SilkS")
			(hide yes)
			(effects
				(font
					(size 1.27 1.27)
				)
			)
		)
		(property "Value" ""
			(at 0 0 90)
			(layer "F.Fab")
			(effects
				(font
					(size 1.27 1.27)
				)
			)
		)
		(duplicate_pad_numbers_are_jumpers no)
		(fp_line
			(start 0.7874 -0.4064)
			(end 0.7874 0.4064)
			(stroke
				(width 0.1524)
				(type default)
			)
			(layer "F.SilkS")
		)
		(fp_line
			(start -0.7874 -0.4064)
			(end 0.7874 -0.4064)
			(stroke
				(width 0.1524)
				(type default)
			)
			(layer "F.SilkS")
		)
		(fp_line
			(start 0.7874 0.4064)
			(end -0.7874 0.4064)
			(stroke
				(width 0.1524)
				(type default)
			)
			(layer "F.SilkS")
		)
		(fp_line
			(start -0.7874 0.4064)
			(end -0.7874 -0.4064)
			(stroke
				(width 0.1524)
				(type default)
			)
			(layer "F.SilkS")
		)
		(fp_line
			(start -0.12065 -0.305054)
			(end -0.12065 -0.2794)
			(stroke
				(width 0.1)
				(type default)
			)
			(layer "F.Fab")
		)
		(fp_line
			(start -0.67945 -0.305054)
			(end -0.12065 -0.305054)
			(stroke
				(width 0.1)
				(type default)
			)
			(layer "F.Fab")
		)
		(fp_line
			(start 0.67945 -0.3048)
			(end 0.67945 0.3048)
			(stroke
				(width 0.1)
				(type default)
			)
			(layer "F.Fab")
		)
		(fp_line
			(start 0.12065 -0.3048)
			(end 0.67945 -0.3048)
			(stroke
				(width 0.1)
				(type default)
			)
			(layer "F.Fab")
		)
		(fp_line
			(start 0.12065 -0.2794)
			(end 0.12065 -0.3048)
			(stroke
				(width 0.1)
				(type default)
			)
			(layer "F.Fab")
		)
		(fp_line
			(start -0.12065 -0.2794)
			(end 0.12065 -0.2794)
			(stroke
				(width 0.1)
				(type default)
			)
			(layer "F.Fab")
		)
		(fp_line
			(start 0.120396 0.2794)
			(end -0.12065 0.2794)
			(stroke
				(width 0.1)
				(type default)
			)
			(layer "F.Fab")
		)
		(fp_line
			(start -0.12065 0.2794)
			(end -0.12065 0.3048)
			(stroke
				(width 0.1)
				(type default)
			)
			(layer "F.Fab")
		)
		(fp_line
			(start 0.67945 0.3048)
			(end 0.120396 0.3048)
			(stroke
				(width 0.1)
				(type default)
			)
			(layer "F.Fab")
		)
		(fp_line
			(start 0.120396 0.3048)
			(end 0.120396 0.2794)
			(stroke
				(width 0.1)
				(type default)
			)
			(layer "F.Fab")
		)
		(fp_line
			(start -0.12065 0.3048)
			(end -0.67945 0.3048)
			(stroke
				(width 0.1)
				(type default)
			)
			(layer "F.Fab")
		)
		(fp_line
			(start -0.67945 0.3048)
			(end -0.67945 -0.305054)
			(stroke
				(width 0.1)
				(type default)
			)
			(layer "F.Fab")
		)
		(pad "1" smd circle
			(at -0.40005 0 90)
			(size 0 0)
			(layers "F.Cu" "F.Mask" "F.Paste")
			(net "P3V3_AUX")
		)
		(pad "2" smd circle
			(at 0.40005 0 90)
			(size 0 0)
			(layers "F.Cu" "F.Mask" "F.Paste")
			(net "FM_SWB_BIC_READY_ISO_N")
		)
	)
)
